FILE_TYPE = CONNECTIVITY;
{Allegro Design Entry HDL 17.2-2016 S081 (4005846) 1/11/2022}
"PAGE_NUMBER" = 11;
0"NC";
END.
